# S9S_MB_2U (Grand Teton) — schematic netlist excerpt (pin names and nets, part order shuffled) for the footprints in the layout excerpt that follows; sources: Cadence DE-HDL packaged netlist, KiCad conversion of 03242023_DA0F0TMBIJ0_F0T_Motherboard_J_brd_V01_OCP.brd

R669  Q_RES  499 1% CHIP  pkg 0402LF  page 230 : A = PVNN_TERM_CPU1 ; B = I3C_SPD_DDREFGH_CPU1_SDA
C512  Q_CAP  47UF 4V 20% X6S  pkg C0805  page 76 : A = PVCCFA_EHV_CPU0 ; B = GND
R3924  Q_RES  0 5% CHIP  pkg 0402LF  page 301 : A = IRQ_SML1_PMBUS_ALERT_N ; B = IRQ_SML1_PMBUS_ALERT

(kicad_pcb
	(version 20260206)
	(generator "pcbnew")
	(generator_version "10.0")
	(general
		(thickness 1.6)
		(legacy_teardrops no)
	)
	(paper "A4")
	(title_block
		(title "03242023_DA0F0TMBIJ0_F0T_Motherboard_J_brd_V01_OCP.brd")
		(comment 1 "Grand Teton / footprints 5129-5131 of 6105")
	)
	(layers
		(0 "F.Cu" signal "TOP")
		(4 "In1.Cu" signal "GND")
		(6 "In2.Cu" signal "IN1")
		(8 "In3.Cu" signal "GND1")
		(10 "In4.Cu" signal "IN2")
		(12 "In5.Cu" signal "GND2")
		(14 "In6.Cu" signal "IN3")
		(16 "In7.Cu" signal "GND3")
		(18 "In8.Cu" signal "VCC")
		(20 "In9.Cu" signal "VCC1")
		(22 "In10.Cu" signal "GND4")
		(24 "In11.Cu" signal "IN4")
		(26 "In12.Cu" signal "GND5")
		(28 "In13.Cu" signal "IN5")
		(30 "In14.Cu" signal "GND6")
		(32 "In15.Cu" signal "IN6")
		(34 "In16.Cu" signal "GND7")
		(2 "B.Cu" signal "BOTTOM")
		(9 "F.Adhes" user "F.Adhesive")
		(11 "B.Adhes" user "B.Adhesive")
		(13 "F.Paste" user "Package Geometry/Pastemask Top")
		(15 "B.Paste" user "Package Geometry/Pastemask Bottom")
		(5 "F.SilkS" user "Ref Des/Silkscreen Top")
		(7 "B.SilkS" user "Ref Des/Silkscreen Bottom")
		(1 "F.Mask" user "Board Geometry/Soldermask Top")
		(3 "B.Mask" user "Board Geometry/Soldermask Bottom")
		(17 "Dwgs.User" user "User.Drawings")
		(19 "Cmts.User" user "User.Comments")
		(21 "Eco1.User" user "User.Eco1")
		(23 "Eco2.User" user "User.Eco2")
		(25 "Edge.Cuts" user "Board Geometry/Outline")
		(27 "Margin" user)
		(31 "F.CrtYd" user "Package Geometry/Place Bound Top")
		(29 "B.CrtYd" user "Package Geometry/Place Bound Bottom")
		(35 "F.Fab" user "Ref Des/Assembly Top")
		(33 "B.Fab" user "Ref Des/Assembly Bottom")
	)
	(footprint ""
		(layer "B.Cu")
		(at 152.339802 -190.359284 -90)
		(property "Reference" "R669"
			(at 0 0 90)
			(layer "B.SilkS")
			(hide yes)
			(effects
				(font
					(size 1.27 1.27)
				)
				(justify mirror)
			)
		)
		(property "Value" ""
			(at 0 0 90)
			(layer "B.Fab")
			(effects
				(font
					(size 1.27 1.27)
				)
				(justify mirror)
			)
		)
		(duplicate_pad_numbers_are_jumpers no)
		(fp_line
			(start -0.7874 0.4064)
			(end 0.7874 0.4064)
			(stroke
				(width 0.1524)
				(type default)
			)
			(layer "B.SilkS")
		)
		(fp_line
			(start 0.7874 0.4064)
			(end 0.7874 -0.4064)
			(stroke
				(width 0.1524)
				(type default)
			)
			(layer "B.SilkS")
		)
		(fp_line
			(start -0.7874 -0.4064)
			(end -0.7874 0.4064)
			(stroke
				(width 0.1524)
				(type default)
			)
			(layer "B.SilkS")
		)
		(fp_line
			(start 0.7874 -0.4064)
			(end -0.7874 -0.4064)
			(stroke
				(width 0.1524)
				(type default)
			)
			(layer "B.SilkS")
		)
		(fp_line
			(start -0.67945 0.3048)
			(end -0.120396 0.3048)
			(stroke
				(width 0.1)
				(type default)
			)
			(layer "B.Fab")
		)
		(fp_line
			(start -0.120396 0.3048)
			(end -0.120396 0.2794)
			(stroke
				(width 0.1)
				(type default)
			)
			(layer "B.Fab")
		)
		(fp_line
			(start 0.12065 0.3048)
			(end 0.67945 0.3048)
			(stroke
				(width 0.1)
				(type default)
			)
			(layer "B.Fab")
		)
		(fp_line
			(start 0.67945 0.3048)
			(end 0.67945 -0.305054)
			(stroke
				(width 0.1)
				(type default)
			)
			(layer "B.Fab")
		)
		(fp_line
			(start -0.120396 0.2794)
			(end 0.12065 0.2794)
			(stroke
				(width 0.1)
				(type default)
			)
			(layer "B.Fab")
		)
		(fp_line
			(start 0.12065 0.2794)
			(end 0.12065 0.3048)
			(stroke
				(width 0.1)
				(type default)
			)
			(layer "B.Fab")
		)
		(fp_line
			(start -0.12065 -0.2794)
			(end -0.12065 -0.3048)
			(stroke
				(width 0.1)
				(type default)
			)
			(layer "B.Fab")
		)
		(fp_line
			(start 0.12065 -0.2794)
			(end -0.12065 -0.2794)
			(stroke
				(width 0.1)
				(type default)
			)
			(layer "B.Fab")
		)
		(fp_line
			(start -0.67945 -0.3048)
			(end -0.67945 0.3048)
			(stroke
				(width 0.1)
				(type default)
			)
			(layer "B.Fab")
		)
		(fp_line
			(start -0.12065 -0.3048)
			(end -0.67945 -0.3048)
			(stroke
				(width 0.1)
				(type default)
			)
			(layer "B.Fab")
		)
		(fp_line
			(start 0.12065 -0.305054)
			(end 0.12065 -0.2794)
			(stroke
				(width 0.1)
				(type default)
			)
			(layer "B.Fab")
		)
		(fp_line
			(start 0.67945 -0.305054)
			(end 0.12065 -0.305054)
			(stroke
				(width 0.1)
				(type default)
			)
			(layer "B.Fab")
		)
		(pad "1" smd circle
			(at 0.40005 0 90)
			(size 0 0)
			(layers "B.Cu" "B.Mask" "B.Paste")
			(net "PVNN_TERM_CPU1")
		)
		(pad "2" smd circle
			(at -0.40005 0 90)
			(size 0 0)
			(layers "B.Cu" "B.Mask" "B.Paste")
			(net "I3C_SPD_DDREFGH_CPU1_SDA")
		)
	)
	(footprint ""
		(layer "B.Cu")
		(at 183.960008 -404.853902 180)
		(property "Reference" "R3924"
			(at 0 0 0)
			(layer "B.SilkS")
			(hide yes)
			(effects
				(font
					(size 1.27 1.27)
				)
				(justify mirror)
			)
		)
		(property "Value" ""
			(at 0 0 0)
			(layer "B.Fab")
			(effects
				(font
					(size 1.27 1.27)
				)
				(justify mirror)
			)
		)
		(duplicate_pad_numbers_are_jumpers no)
		(fp_line
			(start 0.7874 0.4064)
			(end 0.7874 -0.4064)
			(stroke
				(width 0.1524)
				(type default)
			)
			(layer "B.SilkS")
		)
		(fp_line
			(start 0.7874 -0.4064)
			(end -0.7874 -0.4064)
			(stroke
				(width 0.1524)
				(type default)
			)
			(layer "B.SilkS")
		)
		(fp_line
			(start -0.7874 0.4064)
			(end 0.7874 0.4064)
			(stroke
				(width 0.1524)
				(type default)
			)
			(layer "B.SilkS")
		)
		(fp_line
			(start -0.7874 -0.4064)
			(end -0.7874 0.4064)
			(stroke
				(width 0.1524)
				(type default)
			)
			(layer "B.SilkS")
		)
		(fp_line
			(start 0.67945 0.3048)
			(end 0.67945 -0.305054)
			(stroke
				(width 0.1)
				(type default)
			)
			(layer "B.Fab")
		)
		(fp_line
			(start 0.67945 -0.305054)
			(end 0.12065 -0.305054)
			(stroke
				(width 0.1)
				(type default)
			)
			(layer "B.Fab")
		)
		(fp_line
			(start 0.12065 0.3048)
			(end 0.67945 0.3048)
			(stroke
				(width 0.1)
				(type default)
			)
			(layer "B.Fab")
		)
		(fp_line
			(start 0.12065 0.2794)
			(end 0.12065 0.3048)
			(stroke
				(width 0.1)
				(type default)
			)
			(layer "B.Fab")
		)
		(fp_line
			(start 0.12065 -0.2794)
			(end -0.12065 -0.2794)
			(stroke
				(width 0.1)
				(type default)
			)
			(layer "B.Fab")
		)
		(fp_line
			(start 0.12065 -0.305054)
			(end 0.12065 -0.2794)
			(stroke
				(width 0.1)
				(type default)
			)
			(layer "B.Fab")
		)
		(fp_line
			(start -0.120396 0.3048)
			(end -0.120396 0.2794)
			(stroke
				(width 0.1)
				(type default)
			)
			(layer "B.Fab")
		)
		(fp_line
			(start -0.120396 0.2794)
			(end 0.12065 0.2794)
			(stroke
				(width 0.1)
				(type default)
			)
			(layer "B.Fab")
		)
		(fp_line
			(start -0.12065 -0.2794)
			(end -0.12065 -0.3048)
			(stroke
				(width 0.1)
				(type default)
			)
			(layer "B.Fab")
		)
		(fp_line
			(start -0.12065 -0.3048)
			(end -0.67945 -0.3048)
			(stroke
				(width 0.1)
				(type default)
			)
			(layer "B.Fab")
		)
		(fp_line
			(start -0.67945 0.3048)
			(end -0.120396 0.3048)
			(stroke
				(width 0.1)
				(type default)
			)
			(layer "B.Fab")
		)
		(fp_line
			(start -0.67945 -0.3048)
			(end -0.67945 0.3048)
			(stroke
				(width 0.1)
				(type default)
			)
			(layer "B.Fab")
		)
		(pad "1" smd circle
			(at 0.40005 0)
			(size 0 0)
			(layers "B.Cu" "B.Mask" "B.Paste")
			(net "IRQ_SML1_PMBUS_ALERT_N")
		)
		(pad "2" smd circle
			(at -0.40005 0)
			(size 0 0)
			(layers "B.Cu" "B.Mask" "B.Paste")
			(net "IRQ_SML1_PMBUS_ALERT")
		)
	)
	(footprint ""
		(layer "B.Cu")
		(at 352.402902 -212.049614)
		(property "Reference" "C512"
			(at 0 0 0)
			(layer "B.SilkS")
			(hide yes)
			(effects
				(font
					(size 1.27 1.27)
				)
				(justify mirror)
			)
		)
		(property "Value" ""
			(at 0 0 0)
			(layer "B.Fab")
			(effects
				(font
					(size 1.27 1.27)
				)
				(justify mirror)
			)
		)
		(duplicate_pad_numbers_are_jumpers no)
		(fp_line
			(start -1.524 -0.762)
			(end -1.524 0.762)
			(stroke
				(width 0.1524)
				(type default)
			)
			(layer "B.SilkS")
		)
		(fp_line
			(start -1.524 0.762)
			(end 1.524 0.762)
			(stroke
				(width 0.1524)
				(type default)
			)
			(layer "B.SilkS")
		)
		(fp_line
			(start 1.524 -0.762)
			(end -1.524 -0.762)
			(stroke
				(width 0.1524)
				(type default)
			)
			(layer "B.SilkS")
		)
		(fp_line
			(start 1.524 0.762)
			(end 1.524 -0.762)
			(stroke
				(width 0.1524)
				(type default)
			)
			(layer "B.SilkS")
		)
		(fp_line
			(start -1.1049 -0.724916)
			(end 1.1049 -0.724916)
			(stroke
				(width 0.1)
				(type default)
			)
			(layer "B.Fab")
		)
		(fp_line
			(start -1.1049 0.724916)
			(end -1.1049 -0.724916)
			(stroke
				(width 0.1)
				(type default)
			)
			(layer "B.Fab")
		)
		(fp_line
			(start 1.1049 -0.724916)
			(end 1.1049 0.724916)
			(stroke
				(width 0.1)
				(type default)
			)
			(layer "B.Fab")
		)
		(fp_line
			(start 1.1049 0.724916)
			(end -1.1049 0.724916)
			(stroke
				(width 0.1)
				(type default)
			)
			(layer "B.Fab")
		)
		(pad "1" smd rect
			(at 0.889 0)
			(size 1.016 1.27)
			(layers "B.Cu" "B.Mask" "B.Paste")
			(net "PVCCFA_EHV_CPU0")
		)
		(pad "2" smd rect
			(at -0.889 0)
			(size 1.016 1.27)
			(layers "B.Cu" "B.Mask" "B.Paste")
			(net "GND")
		)
	)
)
